# T6G (Grand Teton) — schematic netlist excerpt (pin names and nets, part order shuffled) for the footprints in the layout excerpt that follows; sources: Cadence DE-HDL packaged netlist, KiCad conversion of 04192023_DAF0TMB3IC0_F0TG_MB_C_brd_V02_OCP.brd

PL23  Q_INDUCTOR  90NH/155A IND  pkg SMLF  page 208 : \1\ = SW_PVDD11_S3_P0_SW1 ; \2\ = PVDD11_S3_P0
R745  Q_RES  1K 1% EMPTY  pkg 0201LF  page 331 : A = P1V8_CPU1_RT_1D ; B = RT_CPU1_P1_ADDR2
PR8089  Q_RES  16.9K 1% CHIP  pkg 0402LF  page 189 : A = P5V_AUX_CS ; B = GND

(kicad_pcb
	(version 20260206)
	(generator "pcbnew")
	(generator_version "10.0")
	(general
		(thickness 1.6)
		(legacy_teardrops no)
	)
	(paper "A4")
	(title_block
		(title "04192023_DAF0TMB3IC0_F0TG_MB_C_brd_V02_OCP.brd")
		(comment 1 "Grand Teton / footprints 3439-3441 of 8354")
	)
	(layers
		(0 "F.Cu" signal "TOP")
		(4 "In1.Cu" signal "GND")
		(6 "In2.Cu" signal "IN1")
		(8 "In3.Cu" signal "GND1")
		(10 "In4.Cu" signal "IN2")
		(12 "In5.Cu" signal "GND2")
		(14 "In6.Cu" signal "IN3")
		(16 "In7.Cu" signal "GND3")
		(18 "In8.Cu" signal "VCC")
		(20 "In9.Cu" signal "VCC1")
		(22 "In10.Cu" signal "GND4")
		(24 "In11.Cu" signal "IN4")
		(26 "In12.Cu" signal "GND5")
		(28 "In13.Cu" signal "IN5")
		(30 "In14.Cu" signal "GND6")
		(32 "In15.Cu" signal "IN6")
		(34 "In16.Cu" signal "GND7")
		(2 "B.Cu" signal "BOTTOM")
		(9 "F.Adhes" user "F.Adhesive")
		(11 "B.Adhes" user "B.Adhesive")
		(13 "F.Paste" user "Package Geometry/Pastemask Top")
		(15 "B.Paste" user "Package Geometry/Pastemask Bottom")
		(5 "F.SilkS" user "Ref Des/Silkscreen Top")
		(7 "B.SilkS" user "Ref Des/Silkscreen Bottom")
		(1 "F.Mask" user "Board Geometry/Soldermask Top")
		(3 "B.Mask" user "Board Geometry/Soldermask Bottom")
		(17 "Dwgs.User" user "User.Drawings")
		(19 "Cmts.User" user "User.Comments")
		(21 "Eco1.User" user "User.Eco1")
		(23 "Eco2.User" user "User.Eco2")
		(25 "Edge.Cuts" user "Board Geometry/Outline")
		(27 "Margin" user)
		(31 "F.CrtYd" user "Package Geometry/Place Bound Top")
		(29 "B.CrtYd" user "Package Geometry/Place Bound Bottom")
		(35 "F.Fab" user "Ref Des/Assembly Top")
		(33 "B.Fab" user "Ref Des/Assembly Bottom")
	)
	(footprint ""
		(layer "F.Cu")
		(at 105.222548 -385.5212 90)
		(property "Reference" "R745"
			(at 0 0 90)
			(layer "F.SilkS")
			(hide yes)
			(effects
				(font
					(size 1.27 1.27)
				)
			)
		)
		(property "Value" ""
			(at 0 0 90)
			(layer "F.Fab")
			(effects
				(font
					(size 1.27 1.27)
				)
			)
		)
		(duplicate_pad_numbers_are_jumpers no)
		(fp_line
			(start 0.32512 -0.175006)
			(end 0.32512 0.175006)
			(stroke
				(width 0.1)
				(type default)
			)
			(layer "F.Fab")
		)
		(fp_line
			(start -0.32512 -0.175006)
			(end 0.32512 -0.175006)
			(stroke
				(width 0.1)
				(type default)
			)
			(layer "F.Fab")
		)
		(fp_line
			(start 0.32512 0.175006)
			(end -0.32512 0.175006)
			(stroke
				(width 0.1)
				(type default)
			)
			(layer "F.Fab")
		)
		(fp_line
			(start -0.32512 0.175006)
			(end -0.32512 -0.175006)
			(stroke
				(width 0.1)
				(type default)
			)
			(layer "F.Fab")
		)
		(pad "1" smd rect
			(at -0.2667 0 90)
			(size 0.3048 0.381)
			(layers "F.Cu" "F.Mask" "F.Paste")
			(net "P1V8_CPU1_RT_1D")
		)
		(pad "2" smd rect
			(at 0.2667 0 270)
			(size 0.3048 0.381)
			(layers "F.Cu" "F.Mask" "F.Paste")
			(net "RT_CPU1_P1_ADDR2")
		)
	)
	(footprint ""
		(layer "F.Cu")
		(at 409.450794 -142.009368 180)
		(property "Reference" "PR8089"
			(at 0 0 180)
			(layer "F.SilkS")
			(hide yes)
			(effects
				(font
					(size 1.27 1.27)
				)
			)
		)
		(property "Value" ""
			(at 0 0 180)
			(layer "F.Fab")
			(effects
				(font
					(size 1.27 1.27)
				)
			)
		)
		(duplicate_pad_numbers_are_jumpers no)
		(fp_line
			(start 0.7874 0.4064)
			(end -0.7874 0.4064)
			(stroke
				(width 0.1524)
				(type default)
			)
			(layer "F.SilkS")
		)
		(fp_line
			(start 0.7874 -0.4064)
			(end 0.7874 0.4064)
			(stroke
				(width 0.1524)
				(type default)
			)
			(layer "F.SilkS")
		)
		(fp_line
			(start -0.7874 0.4064)
			(end -0.7874 -0.4064)
			(stroke
				(width 0.1524)
				(type default)
			)
			(layer "F.SilkS")
		)
		(fp_line
			(start -0.7874 -0.4064)
			(end 0.7874 -0.4064)
			(stroke
				(width 0.1524)
				(type default)
			)
			(layer "F.SilkS")
		)
		(fp_line
			(start 0.67945 0.3048)
			(end 0.120396 0.3048)
			(stroke
				(width 0.1)
				(type default)
			)
			(layer "F.Fab")
		)
		(fp_line
			(start 0.67945 -0.3048)
			(end 0.67945 0.3048)
			(stroke
				(width 0.1)
				(type default)
			)
			(layer "F.Fab")
		)
		(fp_line
			(start 0.12065 -0.2794)
			(end 0.12065 -0.3048)
			(stroke
				(width 0.1)
				(type default)
			)
			(layer "F.Fab")
		)
		(fp_line
			(start 0.12065 -0.3048)
			(end 0.67945 -0.3048)
			(stroke
				(width 0.1)
				(type default)
			)
			(layer "F.Fab")
		)
		(fp_line
			(start 0.120396 0.3048)
			(end 0.120396 0.2794)
			(stroke
				(width 0.1)
				(type default)
			)
			(layer "F.Fab")
		)
		(fp_line
			(start 0.120396 0.2794)
			(end -0.12065 0.2794)
			(stroke
				(width 0.1)
				(type default)
			)
			(layer "F.Fab")
		)
		(fp_line
			(start -0.12065 0.3048)
			(end -0.67945 0.3048)
			(stroke
				(width 0.1)
				(type default)
			)
			(layer "F.Fab")
		)
		(fp_line
			(start -0.12065 0.2794)
			(end -0.12065 0.3048)
			(stroke
				(width 0.1)
				(type default)
			)
			(layer "F.Fab")
		)
		(fp_line
			(start -0.12065 -0.2794)
			(end 0.12065 -0.2794)
			(stroke
				(width 0.1)
				(type default)
			)
			(layer "F.Fab")
		)
		(fp_line
			(start -0.12065 -0.305054)
			(end -0.12065 -0.2794)
			(stroke
				(width 0.1)
				(type default)
			)
			(layer "F.Fab")
		)
		(fp_line
			(start -0.67945 0.3048)
			(end -0.67945 -0.305054)
			(stroke
				(width 0.1)
				(type default)
			)
			(layer "F.Fab")
		)
		(fp_line
			(start -0.67945 -0.305054)
			(end -0.12065 -0.305054)
			(stroke
				(width 0.1)
				(type default)
			)
			(layer "F.Fab")
		)
		(pad "1" smd circle
			(at -0.40005 0 180)
			(size 0 0)
			(layers "F.Cu" "F.Mask" "F.Paste")
			(net "P5V_AUX_CS")
		)
		(pad "2" smd circle
			(at 0.40005 0 180)
			(size 0 0)
			(layers "F.Cu" "F.Mask" "F.Paste")
			(net "GND")
		)
	)
	(footprint ""
		(layer "F.Cu")
		(at 423.64406 -342.281764 -90)
		(property "Reference" "PL23"
			(at -2.142236 4.77139 90)
			(unlocked yes)
			(layer "F.SilkS")
			(effects
				(font
					(size 0.7874 0.5842)
					(thickness 0.1524)
				)
				(justify left)
			)
		)
		(property "Value" ""
			(at 0 0 270)
			(layer "F.Fab")
			(effects
				(font
					(size 1.27 1.27)
				)
			)
		)
		(duplicate_pad_numbers_are_jumpers no)
		(fp_line
			(start -4.99999 3.849878)
			(end -4.99999 2.23901)
			(stroke
				(width 0.1524)
				(type default)
			)
			(layer "F.SilkS")
		)
		(fp_line
			(start 4.99999 3.849878)
			(end -4.99999 3.849878)
			(stroke
				(width 0.1524)
				(type default)
			)
			(layer "F.SilkS")
		)
		(fp_line
			(start 4.99999 2.23901)
			(end 4.99999 3.849878)
			(stroke
				(width 0.1524)
				(type default)
			)
			(layer "F.SilkS")
		)
		(fp_line
			(start -4.99999 -2.23901)
			(end -4.99999 -3.849878)
			(stroke
				(width 0.1524)
				(type default)
			)
			(layer "F.SilkS")
		)
		(fp_line
			(start -4.99999 -3.849878)
			(end 4.99999 -3.849878)
			(stroke
				(width 0.1524)
				(type default)
			)
			(layer "F.SilkS")
		)
		(fp_line
			(start 4.99999 -3.849878)
			(end 4.99999 -2.23901)
			(stroke
				(width 0.1524)
				(type default)
			)
			(layer "F.SilkS")
		)
		(fp_line
			(start -4.99999 3.849878)
			(end -4.99999 -3.849878)
			(stroke
				(width 0.1)
				(type default)
			)
			(layer "F.Fab")
		)
		(fp_line
			(start 4.99999 3.849878)
			(end -4.99999 3.849878)
			(stroke
				(width 0.1)
				(type default)
			)
			(layer "F.Fab")
		)
		(fp_line
			(start -4.99999 -3.849878)
			(end 4.99999 -3.849878)
			(stroke
				(width 0.1)
				(type default)
			)
			(layer "F.Fab")
		)
		(fp_line
			(start 4.99999 -3.849878)
			(end 4.99999 3.849878)
			(stroke
				(width 0.1)
				(type default)
			)
			(layer "F.Fab")
		)
		(pad "1" smd rect
			(at -3.299968 0 270)
			(size 3.302 4.2164)
			(layers "F.Cu" "F.Mask" "F.Paste")
			(net "SW_PVDD11_S3_P0_SW1")
		)
		(pad "2" smd rect
			(at 3.299968 0 270)
			(size 3.302 4.2164)
			(layers "F.Cu" "F.Mask" "F.Paste")
			(net "PVDD11_S3_P0")
		)
	)
)
